# S9S_MB_2U (Grand Teton) — schematic netlist excerpt (pin names and nets, part order shuffled) for the footprints in the layout excerpt that follows; sources: Cadence DE-HDL packaged netlist, KiCad conversion of 03242023_DA0F0TMBIJ0_F0T_Motherboard_J_brd_V01_OCP.brd

R4261  Q_RES  240 1% EMPTY  pkg 0402LF  page 119 : A = PD_CPU1_BIST_ENABLE ; B = GND
R4702  Q_RES  560 1% CHIP  pkg 0402LF  page 255 : A = LED_P12V_AUX_R1 ; B = LED_P12V_AUX_R2

(kicad_pcb
	(version 20260206)
	(generator "pcbnew")
	(generator_version "10.0")
	(general
		(thickness 1.6)
		(legacy_teardrops no)
	)
	(paper "A4")
	(title_block
		(title "03242023_DA0F0TMBIJ0_F0T_Motherboard_J_brd_V01_OCP.brd")
		(comment 1 "Grand Teton / footprints 1282-1283 of 6105")
	)
	(layers
		(0 "F.Cu" signal "TOP")
		(4 "In1.Cu" signal "GND")
		(6 "In2.Cu" signal "IN1")
		(8 "In3.Cu" signal "GND1")
		(10 "In4.Cu" signal "IN2")
		(12 "In5.Cu" signal "GND2")
		(14 "In6.Cu" signal "IN3")
		(16 "In7.Cu" signal "GND3")
		(18 "In8.Cu" signal "VCC")
		(20 "In9.Cu" signal "VCC1")
		(22 "In10.Cu" signal "GND4")
		(24 "In11.Cu" signal "IN4")
		(26 "In12.Cu" signal "GND5")
		(28 "In13.Cu" signal "IN5")
		(30 "In14.Cu" signal "GND6")
		(32 "In15.Cu" signal "IN6")
		(34 "In16.Cu" signal "GND7")
		(2 "B.Cu" signal "BOTTOM")
		(9 "F.Adhes" user "F.Adhesive")
		(11 "B.Adhes" user "B.Adhesive")
		(13 "F.Paste" user "Package Geometry/Pastemask Top")
		(15 "B.Paste" user "Package Geometry/Pastemask Bottom")
		(5 "F.SilkS" user "Ref Des/Silkscreen Top")
		(7 "B.SilkS" user "Ref Des/Silkscreen Bottom")
		(1 "F.Mask" user "Board Geometry/Soldermask Top")
		(3 "B.Mask" user "Board Geometry/Soldermask Bottom")
		(17 "Dwgs.User" user "User.Drawings")
		(19 "Cmts.User" user "User.Comments")
		(21 "Eco1.User" user "User.Eco1")
		(23 "Eco2.User" user "User.Eco2")
		(25 "Edge.Cuts" user "Board Geometry/Outline")
		(27 "Margin" user)
		(31 "F.CrtYd" user "Package Geometry/Place Bound Top")
		(29 "B.CrtYd" user "Package Geometry/Place Bound Bottom")
		(35 "F.Fab" user "Ref Des/Assembly Top")
		(33 "B.Fab" user "Ref Des/Assembly Bottom")
	)
	(footprint ""
		(layer "F.Cu")
		(at 367.7412 -74.3458 90)
		(property "Reference" "R4702"
			(at 0 0 90)
			(layer "F.SilkS")
			(hide yes)
			(effects
				(font
					(size 1.27 1.27)
				)
			)
		)
		(property "Value" ""
			(at 0 0 90)
			(layer "F.Fab")
			(effects
				(font
					(size 1.27 1.27)
				)
			)
		)
		(duplicate_pad_numbers_are_jumpers no)
		(fp_line
			(start 0.7874 -0.4064)
			(end 0.7874 0.4064)
			(stroke
				(width 0.1524)
				(type default)
			)
			(layer "F.SilkS")
		)
		(fp_line
			(start -0.7874 -0.4064)
			(end 0.7874 -0.4064)
			(stroke
				(width 0.1524)
				(type default)
			)
			(layer "F.SilkS")
		)
		(fp_line
			(start 0.7874 0.4064)
			(end -0.7874 0.4064)
			(stroke
				(width 0.1524)
				(type default)
			)
			(layer "F.SilkS")
		)
		(fp_line
			(start -0.7874 0.4064)
			(end -0.7874 -0.4064)
			(stroke
				(width 0.1524)
				(type default)
			)
			(layer "F.SilkS")
		)
		(fp_line
			(start -0.12065 -0.305054)
			(end -0.12065 -0.2794)
			(stroke
				(width 0.1)
				(type default)
			)
			(layer "F.Fab")
		)
		(fp_line
			(start -0.67945 -0.305054)
			(end -0.12065 -0.305054)
			(stroke
				(width 0.1)
				(type default)
			)
			(layer "F.Fab")
		)
		(fp_line
			(start 0.67945 -0.3048)
			(end 0.67945 0.3048)
			(stroke
				(width 0.1)
				(type default)
			)
			(layer "F.Fab")
		)
		(fp_line
			(start 0.12065 -0.3048)
			(end 0.67945 -0.3048)
			(stroke
				(width 0.1)
				(type default)
			)
			(layer "F.Fab")
		)
		(fp_line
			(start 0.12065 -0.2794)
			(end 0.12065 -0.3048)
			(stroke
				(width 0.1)
				(type default)
			)
			(layer "F.Fab")
		)
		(fp_line
			(start -0.12065 -0.2794)
			(end 0.12065 -0.2794)
			(stroke
				(width 0.1)
				(type default)
			)
			(layer "F.Fab")
		)
		(fp_line
			(start 0.120396 0.2794)
			(end -0.12065 0.2794)
			(stroke
				(width 0.1)
				(type default)
			)
			(layer "F.Fab")
		)
		(fp_line
			(start -0.12065 0.2794)
			(end -0.12065 0.3048)
			(stroke
				(width 0.1)
				(type default)
			)
			(layer "F.Fab")
		)
		(fp_line
			(start 0.67945 0.3048)
			(end 0.120396 0.3048)
			(stroke
				(width 0.1)
				(type default)
			)
			(layer "F.Fab")
		)
		(fp_line
			(start 0.120396 0.3048)
			(end 0.120396 0.2794)
			(stroke
				(width 0.1)
				(type default)
			)
			(layer "F.Fab")
		)
		(fp_line
			(start -0.12065 0.3048)
			(end -0.67945 0.3048)
			(stroke
				(width 0.1)
				(type default)
			)
			(layer "F.Fab")
		)
		(fp_line
			(start -0.67945 0.3048)
			(end -0.67945 -0.305054)
			(stroke
				(width 0.1)
				(type default)
			)
			(layer "F.Fab")
		)
		(pad "1" smd circle
			(at -0.40005 0 90)
			(size 0 0)
			(layers "F.Cu" "F.Mask" "F.Paste")
			(net "LED_P12V_AUX_R1")
		)
		(pad "2" smd circle
			(at 0.40005 0 90)
			(size 0 0)
			(layers "F.Cu" "F.Mask" "F.Paste")
			(net "LED_P12V_AUX_R2")
		)
	)
	(footprint ""
		(layer "F.Cu")
		(at 88.451182 -180.33873)
		(property "Reference" "R4261"
			(at 0 0 0)
			(layer "F.SilkS")
			(hide yes)
			(effects
				(font
					(size 1.27 1.27)
				)
			)
		)
		(property "Value" ""
			(at 0 0 0)
			(layer "F.Fab")
			(effects
				(font
					(size 1.27 1.27)
				)
			)
		)
		(duplicate_pad_numbers_are_jumpers no)
		(fp_line
			(start -0.7874 -0.4064)
			(end 0.7874 -0.4064)
			(stroke
				(width 0.1524)
				(type default)
			)
			(layer "F.SilkS")
		)
		(fp_line
			(start -0.7874 0.4064)
			(end -0.7874 -0.4064)
			(stroke
				(width 0.1524)
				(type default)
			)
			(layer "F.SilkS")
		)
		(fp_line
			(start 0.7874 -0.4064)
			(end 0.7874 0.4064)
			(stroke
				(width 0.1524)
				(type default)
			)
			(layer "F.SilkS")
		)
		(fp_line
			(start 0.7874 0.4064)
			(end -0.7874 0.4064)
			(stroke
				(width 0.1524)
				(type default)
			)
			(layer "F.SilkS")
		)
		(fp_line
			(start -0.67945 -0.305054)
			(end -0.12065 -0.305054)
			(stroke
				(width 0.1)
				(type default)
			)
			(layer "F.Fab")
		)
		(fp_line
			(start -0.67945 0.3048)
			(end -0.67945 -0.305054)
			(stroke
				(width 0.1)
				(type default)
			)
			(layer "F.Fab")
		)
		(fp_line
			(start -0.12065 -0.305054)
			(end -0.12065 -0.2794)
			(stroke
				(width 0.1)
				(type default)
			)
			(layer "F.Fab")
		)
		(fp_line
			(start -0.12065 -0.2794)
			(end 0.12065 -0.2794)
			(stroke
				(width 0.1)
				(type default)
			)
			(layer "F.Fab")
		)
		(fp_line
			(start -0.12065 0.2794)
			(end -0.12065 0.3048)
			(stroke
				(width 0.1)
				(type default)
			)
			(layer "F.Fab")
		)
		(fp_line
			(start -0.12065 0.3048)
			(end -0.67945 0.3048)
			(stroke
				(width 0.1)
				(type default)
			)
			(layer "F.Fab")
		)
		(fp_line
			(start 0.120396 0.2794)
			(end -0.12065 0.2794)
			(stroke
				(width 0.1)
				(type default)
			)
			(layer "F.Fab")
		)
		(fp_line
			(start 0.120396 0.3048)
			(end 0.120396 0.2794)
			(stroke
				(width 0.1)
				(type default)
			)
			(layer "F.Fab")
		)
		(fp_line
			(start 0.12065 -0.3048)
			(end 0.67945 -0.3048)
			(stroke
				(width 0.1)
				(type default)
			)
			(layer "F.Fab")
		)
		(fp_line
			(start 0.12065 -0.2794)
			(end 0.12065 -0.3048)
			(stroke
				(width 0.1)
				(type default)
			)
			(layer "F.Fab")
		)
		(fp_line
			(start 0.67945 -0.3048)
			(end 0.67945 0.3048)
			(stroke
				(width 0.1)
				(type default)
			)
			(layer "F.Fab")
		)
		(fp_line
			(start 0.67945 0.3048)
			(end 0.120396 0.3048)
			(stroke
				(width 0.1)
				(type default)
			)
			(layer "F.Fab")
		)
		(pad "1" smd circle
			(at -0.40005 0)
			(size 0 0)
			(layers "F.Cu" "F.Mask" "F.Paste")
			(net "PD_CPU1_BIST_ENABLE")
		)
		(pad "2" smd circle
			(at 0.40005 0)
			(size 0 0)
			(layers "F.Cu" "F.Mask" "F.Paste")
			(net "GND")
		)
	)
)
